# S9S_MB_2U (Grand Teton) — schematic netlist excerpt (pin names and nets, part order shuffled) for the footprints in the layout excerpt that follows; sources: Cadence DE-HDL packaged netlist, KiCad conversion of 03242023_DA0F0TMBIJ0_F0T_Motherboard_J_brd_V01_OCP.brd

J21  SCONN288_ADR50017P130CC  SCONN288_ADR50017-P130CC IO  pkg DDR288S_1-1VXB  page 102
  VIN_BULK0  = P12V_S3_AUX_CPU1_NVDIMM
  RFU0  = TP_CHC_CPU1_DIMM1_FRU_0
  VIN_MGMT  = P3V3_AUX
  HSCL  = I3C_SPD_DDRABCD_CPU1_LVC1_SCL_4
  HSDA  = I3C_SPD_DDRABCD_CPU1_LVC1_SDA
  VSS0  = GND
  DQ0_A  = M_C_CPU1_SA_DQ<0>
  VSS1  = GND
  DQ1_A  = M_C_CPU1_SA_DQ<1>
  VSS2  = GND
  DQS0_A_T  = M_C_CPU1_SA_DQS_DP<0>
  DQS0_A_C  = M_C_CPU1_SA_DQS_DN<0>
  VSS3  = GND
  DQ4_A  = M_C_CPU1_SA_DQ<4>
  VSS4  = GND
  DQ5_A  = M_C_CPU1_SA_DQ<5>
  VSS5  = GND
  DQ8_A  = M_C_CPU1_SA_DQ<8>
  VSS6  = GND
  DQ9_A  = M_C_CPU1_SA_DQ<9>
  VSS7  = GND
  DQS1_A_T  = M_C_CPU1_SA_DQS_DP<1>
  DQS1_A_C  = M_C_CPU1_SA_DQS_DN<1>
  VSS8  = GND
  DQ12_A  = M_C_CPU1_SA_DQ<12>
  VSS9  = GND
  DQ13_A  = M_C_CPU1_SA_DQ<13>
  VSS10  = GND
  DQ16_A  = M_C_CPU1_SA_DQ<16>
  VSS11  = GND
  DQ17_A  = M_C_CPU1_SA_DQ<17>
  VSS12  = GND
  DQS2_A_T  = M_C_CPU1_SA_DQS_DP<2>
  DQS2_A_C  = M_C_CPU1_SA_DQS_DN<2>
  VSS13  = GND
  DQ20_A  = M_C_CPU1_SA_DQ<20>
  VSS14  = GND
  DQ21_A  = M_C_CPU1_SA_DQ<21>
  VSS15  = GND
  DQ24_A  = M_C_CPU1_SA_DQ<24>
  VSS16  = GND
  DQ25_A  = M_C_CPU1_SA_DQ<25>
  VSS17  = GND
  DQS3_A_T  = M_C_CPU1_SA_DQS_DP<3>
  DQS3_A_C  = M_C_CPU1_SA_DQS_DN<3>
  VSS18  = GND
  DQ28_A  = M_C_CPU1_SA_DQ<28>
  VSS19  = GND
  DQ29_A  = M_C_CPU1_SA_DQ<29>
  VSS20  = GND
  CB0_A  = M_C_CPU1_SA_CB<0>
  VSS21  = GND
  CB1_A  = M_C_CPU1_SA_CB<1>
  VSS22  = GND
  DQS4_A_T  = M_C_CPU1_SA_DQS_DP<4>
  DQS4_A_C  = M_C_CPU1_SA_DQS_DN<4>
  VSS23  = GND
  CB4_A  = M_C_CPU1_SA_CB<4>
  VSS24  = GND
  CB5_A  = M_C_CPU1_SA_CB<5>
  VSS25  = GND
  ALERT_N  = M_C_CPU1_ALERT_N
  VSS26  = GND
  CS0_A_N  = M_C_CPU1_SA_CS_N<0>
  VSS27  = GND
  CA0_A  = M_C_CPU1_SA_CA<0>
  VSS28  = GND
  CA2_A  = M_C_CPU1_SA_CA<2>
  VSS29  = GND
  CA4_A  = M_C_CPU1_SA_CA<4>
  VSS30  = GND
  CA6_A  = M_C_CPU1_SA_CA<6>
  VSS31  = GND
  PAR_A  = M_C_CPU1_SA_PAR
  VSS32  = GND
  CA0_B  = M_C_CPU1_SB_CA<0>
  VSS33  = GND
  CA2_B  = M_C_CPU1_SB_CA<2>
  VSS34  = GND
  CA4_B  = M_C_CPU1_SB_CA<4>
  VSS35  = GND
  CA6_B  = M_C_CPU1_SB_CA<6>
  VSS36  = GND
  CS0_B_N  = M_C_CPU1_SB_CS_N<0>
  VSS37  = GND
  \lbd||rsp_a_n\  = M_C_CPU1_SA_RSP<0>
  \lbs||rsp_b_n\  = M_C_CPU1_SB_RSP<0>
  VSS38  = GND
  CB4_B  = M_C_CPU1_SB_CB<4>
  VSS39  = GND
  CB5_B  = M_C_CPU1_SB_CB<5>
  VSS40  = GND
  \dqs9_b_t||tdqs9_b_t||dbi4_b_n\  = M_C_CPU1_SB_DQS_DP<9>
  \dqs9_b_c||tdqs9_b_c\  = M_C_CPU1_SB_DQS_DN<9>
  VSS41  = GND
  CB0_B  = M_C_CPU1_SB_CB<0>
  VSS42  = GND
  CB1_B  = M_C_CPU1_SB_CB<1>
  VSS43  = GND
  DQ0_B  = M_C_CPU1_SB_DQ<0>
  VSS44  = GND
  DQ1_B  = M_C_CPU1_SB_DQ<1>
  VSS45  = GND
  DQS0_B_T  = M_C_CPU1_SB_DQS_DP<0>
  DQS0_B_C  = M_C_CPU1_SB_DQS_DN<0>
  VSS46  = GND
  DQ4_B  = M_C_CPU1_SB_DQ<4>
  VSS47  = GND
  DQ5_B  = M_C_CPU1_SB_DQ<5>
  VSS48  = GND
  DQ8_B  = M_C_CPU1_SB_DQ<8>
  VSS49  = GND
  DQ9_B  = M_C_CPU1_SB_DQ<9>
  VSS50  = GND
  DQS1_B_T  = M_C_CPU1_SB_DQS_DP<1>
  DQS1_B_C  = M_C_CPU1_SB_DQS_DN<1>
  VSS51  = GND
  DQ12_B  = M_C_CPU1_SB_DQ<12>
  VSS52  = GND
  DQ13_B  = M_C_CPU1_SB_DQ<13>
  VSS53  = GND
  DQ16_B  = M_C_CPU1_SB_DQ<16>
  VSS54  = GND
  DQ17_B  = M_C_CPU1_SB_DQ<17>
  VSS55  = GND
  DQS2_B_T  = M_C_CPU1_SB_DQS_DP<2>
  DQS2_B_C  = M_C_CPU1_SB_DQS_DN<2>
  VSS56  = GND
  DQ20_B  = M_C_CPU1_SB_DQ<20>
  VSS57  = GND
  DQ21_B  = M_C_CPU1_SB_DQ<21>
  VSS58  = GND
  DQ24_B  = M_C_CPU1_SB_DQ<24>
  VSS59  = GND
  DQ25_B  = M_C_CPU1_SB_DQ<25>
  VSS60  = GND
  DQS3_B_T  = M_C_CPU1_SB_DQS_DP<3>
  DQS3_B_C  = M_C_CPU1_SB_DQS_DN<3>
  VSS61  = GND
  DQ28_B  = M_C_CPU1_SB_DQ<28>
  VSS62  = GND
  DQ29_B  = M_C_CPU1_SB_DQ<29>
  VSS63  = GND
  RFU1  = TP_CHC_CPU1_DIMM1_FRU_1
  VIN_BULK1  = P12V_S3_AUX_CPU1_NVDIMM
  VIN_BULK2  = P12V_S3_AUX_CPU1_NVDIMM
  \pwr_good||fail_n\  = PWRGD_CHC_CPU1_DIMM1
  HSA  = PD_CHC_CPU1_DIMM1_SAA
  RFU2  = TP_CHC_CPU1_DIMM1_FRU_2
  RFU3  = TP_CHC_CPU1_DIMM1_FRU_3
  VSS64  = GND
  DQ2_A  = M_C_CPU1_SA_DQ<2>
  VSS65  = GND
  DQ3_A  = M_C_CPU1_SA_DQ<3>
  VSS66  = GND
  \dqs5_a_c||tdqs5_a_c||dqs5_a_t||tdqs5_a_t\  = M_C_CPU1_SA_DQS_DN<5>
  \dqs5_a_t||tdqs5_a_t\  = M_C_CPU1_SA_DQS_DP<5>
  VSS67  = GND
  DQ6_A  = M_C_CPU1_SA_DQ<6>
  VSS68  = GND
  DQ7_A  = M_C_CPU1_SA_DQ<7>
  VSS69  = GND
  DQ10_A  = M_C_CPU1_SA_DQ<10>
  VSS70  = GND
  DQ11_A  = M_C_CPU1_SA_DQ<11>
  VSS71  = GND
  \dqs6_a_c||tdqs6_a_c||dqs6_a_t||tdqs6_a_t\  = M_C_CPU1_SA_DQS_DN<6>
  \dqs6_a_t||tdqs6_a_t\  = M_C_CPU1_SA_DQS_DP<6>
  VSS72  = GND
  DQ14_A  = M_C_CPU1_SA_DQ<14>
  VSS73  = GND
  DQ15_A  = M_C_CPU1_SA_DQ<15>
  VSS74  = GND
  DQ18_A  = M_C_CPU1_SA_DQ<18>
  VSS75  = GND
  DQ19_A  = M_C_CPU1_SA_DQ<19>
  VSS76  = GND
  \dqs7_a_c||tdqs7_a_c\  = M_C_CPU1_SA_DQS_DN<7>
  \dqs7_a_t||tdqs7_a_t\  = M_C_CPU1_SA_DQS_DP<7>
  VSS77  = GND
  DQ22_A  = M_C_CPU1_SA_DQ<22>
  VSS78  = GND
  DQ23_A  = M_C_CPU1_SA_DQ<23>
  VSS79  = GND
  DQ26_A  = M_C_CPU1_SA_DQ<26>
  VSS80  = GND
  DQ27_A  = M_C_CPU1_SA_DQ<27>
  VSS81  = GND
  \dqs8_a_c||tdqs8_a_c\  = M_C_CPU1_SA_DQS_DN<8>
  \dqs8_a_t||tdqs8_a_t\  = M_C_CPU1_SA_DQS_DP<8>
  VSS82  = GND
  DQ30_A  = M_C_CPU1_SA_DQ<30>
  VSS83  = GND
  DQ31_A  = M_C_CPU1_SA_DQ<31>
  VSS84  = GND
  CB2_A  = M_C_CPU1_SA_CB<2>
  VSS85  = GND
  CB3_A  = M_C_CPU1_SA_CB<3>
  VSS86  = GND
  \dqs9_a_c||tdqs9_a_c\  = M_C_CPU1_SA_DQS_DN<9>
  \dqs9_a_t||tdqs9_a_t\  = M_C_CPU1_SA_DQS_DP<9>
  VSS87  = GND
  CB6_A  = M_C_CPU1_SA_CB<6>
  VSS88  = GND
  CB7_A  = M_C_CPU1_SA_CB<7>
  VSS89  = GND
  RESET_N  = RST_M_CD_CPU1_FPGA_N
  VSS90  = GND
  CS1_A_N  = M_C_CPU1_SA_CS_N<1>
  VSS91  = GND
  CA1_A  = M_C_CPU1_SA_CA<1>
  VSS92  = GND
  CA3_A  = M_C_CPU1_SA_CA<3>
  VSS93  = GND
  CA5_A  = M_C_CPU1_SA_CA<5>
  VSS94  = GND
  CK_T  = M_C_CPU1_CLK_DP<0>
  CK_C  = M_C_CPU1_CLK_DN<0>
  VSS95  = GND
  RFU4  = TP_CHC_CPU1_DIMM1_FRU_4
  CA1_B  = M_C_CPU1_SB_CA<1>
  VSS96  = GND
  CA3_B  = M_C_CPU1_SB_CA<3>
  VSS97  = GND
  CA5_B  = M_C_CPU1_SB_CA<5>
  VSS98  = GND
  PAR_B  = M_C_CPU1_SB_PAR
  VSS99  = GND
  CS1_B_N  = M_C_CPU1_SB_CS_N<1>
  VSS100  = GND
  RFU5  = TP_CHC_CPU1_DIMM1_FRU_5
  RFU6  = TP_CHC_CPU1_DIMM1_FRU_6
  VSS101  = GND
  CB6_B  = M_C_CPU1_SB_CB<6>
  VSS102  = GND
  CB7_B  = M_C_CPU1_SB_CB<7>
  VSS103  = GND
  DQS4_B_C  = M_C_CPU1_SB_DQS_DN<4>
  DQS4_B_T  = M_C_CPU1_SB_DQS_DP<4>
  VSS104  = GND
  CB2_B  = M_C_CPU1_SB_CB<2>
  VSS105  = GND
  CB3_B  = M_C_CPU1_SB_CB<3>
  VSS106  = GND
  DQ2_B  = M_C_CPU1_SB_DQ<2>
  VSS107  = GND
  DQ3_B  = M_C_CPU1_SB_DQ<3>
  VSS108  = GND
  \dqs5_b_c||tdqs5_b_c\  = M_C_CPU1_SB_DQS_DN<5>
  \dqs5_b_t||tdqs5_b_t\  = M_C_CPU1_SB_DQS_DP<5>
  VSS109  = GND
  DQ6_B  = M_C_CPU1_SB_DQ<6>
  VSS110  = GND
  DQ7_B  = M_C_CPU1_SB_DQ<7>
  VSS111  = GND
  DQ10_B  = M_C_CPU1_SB_DQ<10>
  VSS112  = GND
  DQ11_B  = M_C_CPU1_SB_DQ<11>
  VSS113  = GND
  \dqs6_b_c||tdqs6_b_c\  = M_C_CPU1_SB_DQS_DN<6>
  \dqs6_b_t||tdqs6_b_t\  = M_C_CPU1_SB_DQS_DP<6>
  VSS114  = GND
  DQ14_B  = M_C_CPU1_SB_DQ<14>
  VSS115  = GND
  DQ15_B  = M_C_CPU1_SB_DQ<15>
  VSS116  = GND
  DQ18_B  = M_C_CPU1_SB_DQ<18>
  VSS117  = GND
  DQ19_B  = M_C_CPU1_SB_DQ<19>
  VSS118  = GND
  \dqs7_b_c||tdqs7_b_c\  = M_C_CPU1_SB_DQS_DN<7>
  \dqs7_b_t||tdqs7_b_t\  = M_C_CPU1_SB_DQS_DP<7>
  VSS119  = GND
  DQ22_B  = M_C_CPU1_SB_DQ<22>
  VSS120  = GND
  DQ23_B  = M_C_CPU1_SB_DQ<23>
  VSS121  = GND
  DQ26_B  = M_C_CPU1_SB_DQ<26>
  VSS122  = GND
  DQ27_B  = M_C_CPU1_SB_DQ<27>
  VSS123  = GND
  \dqs8_b_c||tdqs8_b_c\  = M_C_CPU1_SB_DQS_DN<8>
  \dqs8_b_t||tdqs8_b_t\  = M_C_CPU1_SB_DQS_DP<8>
  VSS124  = GND
  DQ30_B  = M_C_CPU1_SB_DQ<30>
  VSS125  = GND
  DQ31_B  = M_C_CPU1_SB_DQ<31>
  VSS126  = GND
  G1  = GND
  G2  = GND
  G3  = GND

(kicad_pcb
	(version 20260206)
	(generator "pcbnew")
	(generator_version "10.0")
	(general
		(thickness 1.6)
		(legacy_teardrops no)
	)
	(paper "A4")
	(title_block
		(title "03242023_DA0F0TMBIJ0_F0T_Motherboard_J_brd_V01_OCP.brd")
		(comment 1 "Grand Teton / footprint 663 of 6105 (J21), pads 229-274 of 291")
	)
	(layers
		(0 "F.Cu" signal "TOP")
		(4 "In1.Cu" signal "GND")
		(6 "In2.Cu" signal "IN1")
		(8 "In3.Cu" signal "GND1")
		(10 "In4.Cu" signal "IN2")
		(12 "In5.Cu" signal "GND2")
		(14 "In6.Cu" signal "IN3")
		(16 "In7.Cu" signal "GND3")
		(18 "In8.Cu" signal "VCC")
		(20 "In9.Cu" signal "VCC1")
		(22 "In10.Cu" signal "GND4")
		(24 "In11.Cu" signal "IN4")
		(26 "In12.Cu" signal "GND5")
		(28 "In13.Cu" signal "IN5")
		(30 "In14.Cu" signal "GND6")
		(32 "In15.Cu" signal "IN6")
		(34 "In16.Cu" signal "GND7")
		(2 "B.Cu" signal "BOTTOM")
		(9 "F.Adhes" user "F.Adhesive")
		(11 "B.Adhes" user "B.Adhesive")
		(13 "F.Paste" user "Package Geometry/Pastemask Top")
		(15 "B.Paste" user "Package Geometry/Pastemask Bottom")
		(5 "F.SilkS" user "Ref Des/Silkscreen Top")
		(7 "B.SilkS" user "Ref Des/Silkscreen Bottom")
		(1 "F.Mask" user "Board Geometry/Soldermask Top")
		(3 "B.Mask" user "Board Geometry/Soldermask Bottom")
		(17 "Dwgs.User" user "User.Drawings")
		(19 "Cmts.User" user "User.Comments")
		(21 "Eco1.User" user "User.Eco1")
		(23 "Eco2.User" user "User.Eco2")
		(25 "Edge.Cuts" user "Board Geometry/Outline")
		(27 "Margin" user)
		(31 "F.CrtYd" user "Package Geometry/Place Bound Top")
		(29 "B.CrtYd" user "Package Geometry/Place Bound Bottom")
		(35 "F.Fab" user "Ref Des/Assembly Top")
		(33 "B.Fab" user "Ref Des/Assembly Bottom")
	)
	(footprint ""
		(layer "F.Cu")
		(at 25.27808 -258.091686)
		(property "Reference" "J21"
			(at -0.325882 -81.821274 0)
			(unlocked yes)
			(layer "F.SilkS")
			(effects
				(font
					(size 0.7874 0.5842)
					(thickness 0.1524)
				)
				(justify left)
			)
		)
		(property "Value" ""
			(at 0 0 0)
			(layer "F.Fab")
			(effects
				(font
					(size 1.27 1.27)
				)
			)
		)
		(duplicate_pad_numbers_are_jumpers no)
		(pad "229" smd rect
			(at 2.050034 13.17498 270)
			(size 0.519938 1.4986)
			(layers "F.Cu" "F.Mask" "F.Paste")
			(net "M_C_CPU1_SB_CS_N<1>")
		)
		(pad "230" smd rect
			(at 2.050034 14.025118 270)
			(size 0.519938 1.4986)
			(layers "F.Cu" "F.Mask" "F.Paste")
			(net "GND")
		)
		(pad "231" smd rect
			(at 2.050034 14.875002 270)
			(size 0.519938 1.4986)
			(layers "F.Cu" "F.Mask" "F.Paste")
			(net "TP_CHC_CPU1_DIMM1_FRU_5")
		)
		(pad "232" smd rect
			(at 2.050034 15.724886 270)
			(size 0.519938 1.4986)
			(layers "F.Cu" "F.Mask" "F.Paste")
			(net "TP_CHC_CPU1_DIMM1_FRU_6")
		)
		(pad "233" smd rect
			(at 2.050034 16.575024 270)
			(size 0.519938 1.4986)
			(layers "F.Cu" "F.Mask" "F.Paste")
			(net "GND")
		)
		(pad "234" smd rect
			(at 2.050034 17.424908 270)
			(size 0.519938 1.4986)
			(layers "F.Cu" "F.Mask" "F.Paste")
			(net "M_C_CPU1_SB_CB<6>")
		)
		(pad "235" smd rect
			(at 2.050034 18.275046 270)
			(size 0.519938 1.4986)
			(layers "F.Cu" "F.Mask" "F.Paste")
			(net "GND")
		)
		(pad "236" smd rect
			(at 2.050034 19.12493 270)
			(size 0.519938 1.4986)
			(layers "F.Cu" "F.Mask" "F.Paste")
			(net "M_C_CPU1_SB_CB<7>")
		)
		(pad "237" smd rect
			(at 2.050034 19.975068 270)
			(size 0.519938 1.4986)
			(layers "F.Cu" "F.Mask" "F.Paste")
			(net "GND")
		)
		(pad "238" smd rect
			(at 2.050034 20.824952 270)
			(size 0.519938 1.4986)
			(layers "F.Cu" "F.Mask" "F.Paste")
			(net "M_C_CPU1_SB_DQS_DN<4>")
		)
		(pad "239" smd rect
			(at 2.050034 21.67509 270)
			(size 0.519938 1.4986)
			(layers "F.Cu" "F.Mask" "F.Paste")
			(net "M_C_CPU1_SB_DQS_DP<4>")
		)
		(pad "240" smd rect
			(at 2.050034 22.524974 270)
			(size 0.519938 1.4986)
			(layers "F.Cu" "F.Mask" "F.Paste")
			(net "GND")
		)
		(pad "241" smd rect
			(at 2.050034 23.375112 270)
			(size 0.519938 1.4986)
			(layers "F.Cu" "F.Mask" "F.Paste")
			(net "M_C_CPU1_SB_CB<2>")
		)
		(pad "242" smd rect
			(at 2.050034 24.224996 270)
			(size 0.519938 1.4986)
			(layers "F.Cu" "F.Mask" "F.Paste")
			(net "GND")
		)
		(pad "243" smd rect
			(at 2.050034 25.07488 270)
			(size 0.519938 1.4986)
			(layers "F.Cu" "F.Mask" "F.Paste")
			(net "M_C_CPU1_SB_CB<3>")
		)
		(pad "244" smd rect
			(at 2.050034 25.925018 270)
			(size 0.519938 1.4986)
			(layers "F.Cu" "F.Mask" "F.Paste")
			(net "GND")
		)
		(pad "245" smd rect
			(at 2.050034 26.774902 270)
			(size 0.519938 1.4986)
			(layers "F.Cu" "F.Mask" "F.Paste")
			(net "M_C_CPU1_SB_DQ<2>")
		)
		(pad "246" smd rect
			(at 2.050034 27.62504 270)
			(size 0.519938 1.4986)
			(layers "F.Cu" "F.Mask" "F.Paste")
			(net "GND")
		)
		(pad "247" smd rect
			(at 2.050034 28.474924 270)
			(size 0.519938 1.4986)
			(layers "F.Cu" "F.Mask" "F.Paste")
			(net "M_C_CPU1_SB_DQ<3>")
		)
		(pad "248" smd rect
			(at 2.050034 29.325062 270)
			(size 0.519938 1.4986)
			(layers "F.Cu" "F.Mask" "F.Paste")
			(net "GND")
		)
		(pad "249" smd rect
			(at 2.050034 30.174946 270)
			(size 0.519938 1.4986)
			(layers "F.Cu" "F.Mask" "F.Paste")
			(net "M_C_CPU1_SB_DQS_DN<5>")
		)
		(pad "250" smd rect
			(at 2.050034 31.025084 270)
			(size 0.519938 1.4986)
			(layers "F.Cu" "F.Mask" "F.Paste")
			(net "M_C_CPU1_SB_DQS_DP<5>")
		)
		(pad "251" smd rect
			(at 2.050034 31.874968 270)
			(size 0.519938 1.4986)
			(layers "F.Cu" "F.Mask" "F.Paste")
			(net "GND")
		)
		(pad "252" smd rect
			(at 2.050034 32.725106 270)
			(size 0.519938 1.4986)
			(layers "F.Cu" "F.Mask" "F.Paste")
			(net "M_C_CPU1_SB_DQ<6>")
		)
		(pad "253" smd rect
			(at 2.050034 33.57499 270)
			(size 0.519938 1.4986)
			(layers "F.Cu" "F.Mask" "F.Paste")
			(net "GND")
		)
		(pad "254" smd rect
			(at 2.050034 34.425128 270)
			(size 0.519938 1.4986)
			(layers "F.Cu" "F.Mask" "F.Paste")
			(net "M_C_CPU1_SB_DQ<7>")
		)
		(pad "255" smd rect
			(at 2.050034 35.275012 270)
			(size 0.519938 1.4986)
			(layers "F.Cu" "F.Mask" "F.Paste")
			(net "GND")
		)
		(pad "256" smd rect
			(at 2.050034 36.124896 270)
			(size 0.519938 1.4986)
			(layers "F.Cu" "F.Mask" "F.Paste")
			(net "M_C_CPU1_SB_DQ<10>")
		)
		(pad "257" smd rect
			(at 2.050034 36.975034 270)
			(size 0.519938 1.4986)
			(layers "F.Cu" "F.Mask" "F.Paste")
			(net "GND")
		)
		(pad "258" smd rect
			(at 2.050034 37.824918 270)
			(size 0.519938 1.4986)
			(layers "F.Cu" "F.Mask" "F.Paste")
			(net "M_C_CPU1_SB_DQ<11>")
		)
		(pad "259" smd rect
			(at 2.050034 38.675056 270)
			(size 0.519938 1.4986)
			(layers "F.Cu" "F.Mask" "F.Paste")
			(net "GND")
		)
		(pad "260" smd rect
			(at 2.050034 39.52494 270)
			(size 0.519938 1.4986)
			(layers "F.Cu" "F.Mask" "F.Paste")
			(net "M_C_CPU1_SB_DQS_DN<6>")
		)
		(pad "261" smd rect
			(at 2.050034 40.375078 270)
			(size 0.519938 1.4986)
			(layers "F.Cu" "F.Mask" "F.Paste")
			(net "M_C_CPU1_SB_DQS_DP<6>")
		)
		(pad "262" smd rect
			(at 2.050034 41.224962 270)
			(size 0.519938 1.4986)
			(layers "F.Cu" "F.Mask" "F.Paste")
			(net "GND")
		)
		(pad "263" smd rect
			(at 2.050034 42.0751 270)
			(size 0.519938 1.4986)
			(layers "F.Cu" "F.Mask" "F.Paste")
			(net "M_C_CPU1_SB_DQ<14>")
		)
		(pad "264" smd rect
			(at 2.050034 42.924984 270)
			(size 0.519938 1.4986)
			(layers "F.Cu" "F.Mask" "F.Paste")
			(net "GND")
		)
		(pad "265" smd rect
			(at 2.050034 43.775122 270)
			(size 0.519938 1.4986)
			(layers "F.Cu" "F.Mask" "F.Paste")
			(net "M_C_CPU1_SB_DQ<15>")
		)
		(pad "266" smd rect
			(at 2.050034 44.625006 270)
			(size 0.519938 1.4986)
			(layers "F.Cu" "F.Mask" "F.Paste")
			(net "GND")
		)
		(pad "267" smd rect
			(at 2.050034 45.47489 270)
			(size 0.519938 1.4986)
			(layers "F.Cu" "F.Mask" "F.Paste")
			(net "M_C_CPU1_SB_DQ<18>")
		)
		(pad "268" smd rect
			(at 2.050034 46.325028 270)
			(size 0.519938 1.4986)
			(layers "F.Cu" "F.Mask" "F.Paste")
			(net "GND")
		)
		(pad "269" smd rect
			(at 2.050034 47.174912 270)
			(size 0.519938 1.4986)
			(layers "F.Cu" "F.Mask" "F.Paste")
			(net "M_C_CPU1_SB_DQ<19>")
		)
		(pad "270" smd rect
			(at 2.050034 48.02505 270)
			(size 0.519938 1.4986)
			(layers "F.Cu" "F.Mask" "F.Paste")
			(net "GND")
		)
		(pad "271" smd rect
			(at 2.050034 48.874934 270)
			(size 0.519938 1.4986)
			(layers "F.Cu" "F.Mask" "F.Paste")
			(net "M_C_CPU1_SB_DQS_DN<7>")
		)
		(pad "272" smd rect
			(at 2.050034 49.725072 270)
			(size 0.519938 1.4986)
			(layers "F.Cu" "F.Mask" "F.Paste")
			(net "M_C_CPU1_SB_DQS_DP<7>")
		)
		(pad "273" smd rect
			(at 2.050034 50.574956 270)
			(size 0.519938 1.4986)
			(layers "F.Cu" "F.Mask" "F.Paste")
			(net "GND")
		)
		(pad "274" smd rect
			(at 2.050034 51.425094 270)
			(size 0.519938 1.4986)
			(layers "F.Cu" "F.Mask" "F.Paste")
			(net "M_C_CPU1_SB_DQ<22>")
		)
	)
)
